(kicad_pcb
	(version 20260206)
	(generator "pcbnew")
	(generator_version "10.0")
	(general
		(thickness 1.6)
		(legacy_teardrops no)
	)
	(paper "A4")
	(title_block
		(title "Bryce Canyon_IOM_IOC_16318-2_OCP.brd")
		(comment 1 "Bryce Canyon / footprints 368-375 of 1605")
	)
	(layers
		(0 "F.Cu" signal "TOP")
		(4 "In1.Cu" signal "L2GND")
		(6 "In2.Cu" signal "L3")
		(8 "In3.Cu" signal "L4VCC")
		(10 "In4.Cu" signal "L5VCC")
		(12 "In5.Cu" signal "L6")
		(14 "In6.Cu" signal "L7GND")
		(2 "B.Cu" signal "BOTTOM")
		(9 "F.Adhes" user "F.Adhesive")
		(11 "B.Adhes" user "B.Adhesive")
		(13 "F.Paste" user "Package Geometry/Pastemask Top")
		(15 "B.Paste" user "Package Geometry/Pastemask Bottom")
		(5 "F.SilkS" user "Ref Des/Silkscreen Top")
		(7 "B.SilkS" user "Ref Des/Silkscreen Bottom")
		(1 "F.Mask" user "Board Geometry/Soldermask Top")
		(3 "B.Mask" user "Board Geometry/Soldermask Bottom")
		(17 "Dwgs.User" user "User.Drawings")
		(19 "Cmts.User" user "User.Comments")
		(21 "Eco1.User" user "User.Eco1")
		(23 "Eco2.User" user "User.Eco2")
		(25 "Edge.Cuts" user "Board Geometry/Outline")
		(27 "Margin" user)
		(31 "F.CrtYd" user "Package Geometry/Place Bound Top")
		(29 "B.CrtYd" user "Package Geometry/Place Bound Bottom")
		(35 "F.Fab" user "Ref Des/Assembly Top")
		(33 "B.Fab" user "Ref Des/Assembly Bottom")
	)
	(footprint ""
		(layer "F.Cu")
		(at 50.11801 -158.520638 180)
		(property "Reference" "R298"
			(at 0 0 180)
			(layer "F.SilkS")
			(hide yes)
			(effects
				(font
					(size 1.27 1.27)
				)
			)
		)
		(property "Value" "0R2J-2-GP"
			(at 0.064008 -3.993896 180)
			(unlocked yes)
			(layer "F.Fab")
			(hide yes)
			(effects
				(font
					(size 1.016 1.016)
					(thickness 0.1524)
				)
			)
		)
		(property "Device Type" "R402H16"
			(at 0.064008 -5.517896 180)
			(unlocked yes)
			(layer "F.Fab")
			(hide yes)
			(effects
				(font
					(size 1.016 1.016)
					(thickness 0.1524)
				)
			)
		)
		(duplicate_pad_numbers_are_jumpers no)
		(fp_line
			(start 0.508 -0.9398)
			(end -0.508 -0.9398)
			(stroke
				(width 0.1524)
				(type default)
			)
			(layer "F.SilkS")
		)
		(fp_line
			(start -0.508 -0.9398)
			(end -0.508 0.9398)
			(stroke
				(width 0.1524)
				(type default)
			)
			(layer "F.SilkS")
		)
		(fp_rect
			(start -0.508 0.9398)
			(end 0.508 -0.9398)
			(stroke
				(width 0)
				(type default)
			)
			(fill no)
			(layer "F.CrtYd")
		)
		(fp_rect
			(start -0.508 0.9398)
			(end 0.508 -0.9398)
			(stroke
				(width 0)
				(type default)
			)
			(fill no)
			(layer "F.Fab")
		)
		(pad "1" smd custom
			(at 0 -0.4445 180)
			(size 0.1397 0.1397)
			(layers "F.Cu" "F.Mask" "F.Paste")
			(net "UART_BMC_R_RX")
			(options
				(clearance outline)
				(anchor circle)
			)
			(primitives
				(gr_poly
					(pts
						(arc
							(start -0.1778 -0.2794)
							(mid -0.249642 -0.249642)
							(end -0.2794 -0.1778)
						)
						(arc
							(start -0.2794 0.1778)
							(mid -0.249642 0.249642)
							(end -0.1778 0.2794)
						)
						(arc
							(start 0.1778 0.2794)
							(mid 0.249642 0.249642)
							(end 0.2794 0.1778)
						)
						(arc
							(start 0.2794 -0.1778)
							(mid 0.249642 -0.249642)
							(end 0.1778 -0.2794)
						)
					)
					(width 0)
					(fill yes)
				)
			)
		)
		(pad "2" smd custom
			(at 0 0.4445 180)
			(size 0.1397 0.1397)
			(layers "F.Cu" "F.Mask" "F.Paste")
			(net "UART_BMC_RX")
			(options
				(clearance outline)
				(anchor circle)
			)
			(primitives
				(gr_poly
					(pts
						(arc
							(start -0.1778 -0.2794)
							(mid -0.249642 -0.249642)
							(end -0.2794 -0.1778)
						)
						(arc
							(start -0.2794 0.1778)
							(mid -0.249642 0.249642)
							(end -0.1778 0.2794)
						)
						(arc
							(start 0.1778 0.2794)
							(mid 0.249642 0.249642)
							(end 0.2794 0.1778)
						)
						(arc
							(start 0.2794 -0.1778)
							(mid 0.249642 -0.249642)
							(end 0.1778 -0.2794)
						)
					)
					(width 0)
					(fill yes)
				)
			)
		)
	)
	(footprint ""
		(layer "F.Cu")
		(at 88.107774 -167.71747)
		(property "Reference" "Q11"
			(at 0 0 0)
			(layer "F.SilkS")
			(hide yes)
			(effects
				(font
					(size 1.27 1.27)
				)
			)
		)
		(property "Value" "2N7002K-1-GP"
			(at 0.127 -8.9662 0)
			(unlocked yes)
			(layer "F.Fab")
			(hide yes)
			(effects
				(font
					(size 1.016 1.016)
					(thickness 0.1524)
				)
			)
		)
		(property "Device Type" "SOT23DGS2D4H44"
			(at 0.127 -10.4902 0)
			(unlocked yes)
			(layer "F.Fab")
			(hide yes)
			(effects
				(font
					(size 1.016 1.016)
					(thickness 0.1524)
				)
			)
		)
		(duplicate_pad_numbers_are_jumpers no)
		(fp_line
			(start -1.651 -1.778)
			(end -1.651 1.778)
			(stroke
				(width 0.1524)
				(type default)
			)
			(layer "F.SilkS")
		)
		(fp_line
			(start -1.651 1.778)
			(end 1.651 1.778)
			(stroke
				(width 0.1524)
				(type default)
			)
			(layer "F.SilkS")
		)
		(fp_line
			(start 1.651 -1.778)
			(end -1.651 -1.778)
			(stroke
				(width 0.1524)
				(type default)
			)
			(layer "F.SilkS")
		)
		(fp_line
			(start 1.651 1.778)
			(end 1.651 -1.778)
			(stroke
				(width 0.1524)
				(type default)
			)
			(layer "F.SilkS")
		)
		(fp_poly
			(pts
				(xy -1.778 1.8796) (xy -1.778 -1.8796) (xy 1.778 -1.8796) (xy 1.778 1.8796)
			)
			(stroke
				(width 0)
				(type default)
			)
			(fill no)
			(layer "F.CrtYd")
		)
		(fp_poly
			(pts
				(xy -1.778 1.8796) (xy -1.778 -1.8796) (xy 1.778 -1.8796) (xy 1.778 1.8796)
			)
			(stroke
				(width 0)
				(type default)
			)
			(fill no)
			(layer "F.Fab")
		)
		(pad "D" smd custom
			(at 0 -0.9525)
			(size 0.1905 0.1905)
			(layers "F.Cu" "F.Mask" "F.Paste")
			(net "P1V15_STBY_PG_G")
			(options
				(clearance outline)
				(anchor circle)
			)
			(primitives
				(gr_poly
					(pts
						(arc
							(start -0.1778 0.5715)
							(mid -0.321484 0.511984)
							(end -0.381 0.3683)
						)
						(arc
							(start -0.381 -0.3683)
							(mid -0.321484 -0.511984)
							(end -0.1778 -0.5715)
						)
						(arc
							(start 0.1778 -0.5715)
							(mid 0.321484 -0.511984)
							(end 0.381 -0.3683)
						)
						(arc
							(start 0.381 0.3683)
							(mid 0.321484 0.511984)
							(end 0.1778 0.5715)
						)
					)
					(width 0)
					(fill yes)
				)
			)
		)
		(pad "G" smd custom
			(at -0.98425 0.9525)
			(size 0.1905 0.1905)
			(layers "F.Cu" "F.Mask" "F.Paste")
			(net "P1V15_STBY_PG")
			(options
				(clearance outline)
				(anchor circle)
			)
			(primitives
				(gr_poly
					(pts
						(arc
							(start -0.1778 0.5715)
							(mid -0.321484 0.511984)
							(end -0.381 0.3683)
						)
						(arc
							(start -0.381 -0.3683)
							(mid -0.321484 -0.511984)
							(end -0.1778 -0.5715)
						)
						(arc
							(start 0.1778 -0.5715)
							(mid 0.321484 -0.511984)
							(end 0.381 -0.3683)
						)
						(arc
							(start 0.381 0.3683)
							(mid 0.321484 0.511984)
							(end 0.1778 0.5715)
						)
					)
					(width 0)
					(fill yes)
				)
			)
		)
		(pad "S" smd custom
			(at 0.98425 0.9525)
			(size 0.1905 0.1905)
			(layers "F.Cu" "F.Mask" "F.Paste")
			(net "GND")
			(options
				(clearance outline)
				(anchor circle)
			)
			(primitives
				(gr_poly
					(pts
						(arc
							(start -0.1778 0.5715)
							(mid -0.321484 0.511984)
							(end -0.381 0.3683)
						)
						(arc
							(start -0.381 -0.3683)
							(mid -0.321484 -0.511984)
							(end -0.1778 -0.5715)
						)
						(arc
							(start 0.1778 -0.5715)
							(mid 0.321484 -0.511984)
							(end 0.381 -0.3683)
						)
						(arc
							(start 0.381 0.3683)
							(mid 0.321484 0.511984)
							(end 0.1778 0.5715)
						)
					)
					(width 0)
					(fill yes)
				)
			)
		)
	)
	(footprint ""
		(layer "F.Cu")
		(at 40.2209 -159.77616)
		(property "Reference" "TP188"
			(at 0 0 0)
			(layer "F.SilkS")
			(hide yes)
			(effects
				(font
					(size 1.27 1.27)
				)
			)
		)
		(property "Value" "TPAD28-2-GP"
			(at -0.0127 -1.6637 0)
			(unlocked yes)
			(layer "F.Fab")
			(hide yes)
			(effects
				(font
					(size 1.016 1.016)
					(thickness 0.1524)
				)
			)
		)
		(property "Device Type" "TPAD28"
			(at -0.0127 -3.1877 0)
			(unlocked yes)
			(layer "F.Fab")
			(hide yes)
			(effects
				(font
					(size 1.016 1.016)
					(thickness 0.1524)
				)
			)
		)
		(duplicate_pad_numbers_are_jumpers no)
		(fp_poly
			(pts
				(arc
					(start 0.3556 0)
					(mid -0.3556 0)
					(end 0.3556 0)
				)
			)
			(stroke
				(width 0)
				(type default)
			)
			(fill no)
			(layer "F.CrtYd")
		)
		(fp_poly
			(pts
				(arc
					(start 0.6096 0)
					(mid -0.6096 0)
					(end 0.6096 0)
				)
			)
			(stroke
				(width 0)
				(type default)
			)
			(fill no)
			(layer "F.Fab")
		)
		(pad "1" smd circle
			(at 0 0)
			(size 0.7112 0.7112)
			(layers "F.Cu" "F.Mask" "F.Paste")
			(net "TP_BMC_GPIOL2")
		)
	)
	(footprint ""
		(layer "F.Cu")
		(at 182.7022 -153.3398 90)
		(property "Reference" "C156"
			(at 0 0 90)
			(layer "F.SilkS")
			(hide yes)
			(effects
				(font
					(size 1.27 1.27)
				)
			)
		)
		(property "Value" "SC1U16V3KX-5GP"
			(at 0 -2.8194 90)
			(unlocked yes)
			(layer "F.Fab")
			(hide yes)
			(effects
				(font
					(size 1.016 1.016)
					(thickness 0.1524)
				)
			)
		)
		(property "Device Type" "C603H36"
			(at 0 -4.3434 90)
			(unlocked yes)
			(layer "F.Fab")
			(hide yes)
			(effects
				(font
					(size 1.016 1.016)
					(thickness 0.1524)
				)
			)
		)
		(duplicate_pad_numbers_are_jumpers no)
		(fp_line
			(start 0.508 0)
			(end -0.508 0)
			(stroke
				(width 0.2032)
				(type default)
			)
			(layer "F.SilkS")
		)
		(fp_rect
			(start -0.5842 1.3335)
			(end 0.5842 -1.3335)
			(stroke
				(width 0)
				(type default)
			)
			(fill no)
			(layer "F.CrtYd")
		)
		(fp_rect
			(start -0.5842 1.3335)
			(end 0.5842 -1.3335)
			(stroke
				(width 0)
				(type default)
			)
			(fill no)
			(layer "F.Fab")
		)
		(pad "1" smd custom
			(at 0 -0.762 90)
			(size 0.2159 0.2159)
			(layers "F.Cu" "F.Mask" "F.Paste")
			(net "P5V_EN_R")
			(options
				(clearance outline)
				(anchor circle)
			)
			(primitives
				(gr_poly
					(pts
						(arc
							(start -0.3302 -0.4318)
							(mid -0.402042 -0.402042)
							(end -0.4318 -0.3302)
						)
						(arc
							(start -0.4318 0.3302)
							(mid -0.402042 0.402042)
							(end -0.3302 0.4318)
						)
						(arc
							(start 0.3302 0.4318)
							(mid 0.402042 0.402042)
							(end 0.4318 0.3302)
						)
						(arc
							(start 0.4318 -0.3302)
							(mid 0.402042 -0.402042)
							(end 0.3302 -0.4318)
						)
					)
					(width 0)
					(fill yes)
				)
			)
		)
		(pad "2" smd custom
			(at 0 0.762 90)
			(size 0.2159 0.2159)
			(layers "F.Cu" "F.Mask" "F.Paste")
			(net "GND")
			(options
				(clearance outline)
				(anchor circle)
			)
			(primitives
				(gr_poly
					(pts
						(arc
							(start -0.3302 -0.4318)
							(mid -0.402042 -0.402042)
							(end -0.4318 -0.3302)
						)
						(arc
							(start -0.4318 0.3302)
							(mid -0.402042 0.402042)
							(end -0.3302 0.4318)
						)
						(arc
							(start 0.3302 0.4318)
							(mid 0.402042 0.402042)
							(end 0.4318 0.3302)
						)
						(arc
							(start 0.4318 -0.3302)
							(mid 0.402042 -0.402042)
							(end 0.3302 -0.4318)
						)
					)
					(width 0)
					(fill yes)
				)
			)
		)
	)
	(footprint ""
		(layer "F.Cu")
		(at 70.3961 -153.0858 -90)
		(property "Reference" "R780"
			(at 0 0 270)
			(layer "F.SilkS")
			(hide yes)
			(effects
				(font
					(size 1.27 1.27)
				)
			)
		)
		(property "Value" "33R2J-2-GP"
			(at 0.064008 -3.993896 270)
			(unlocked yes)
			(layer "F.Fab")
			(hide yes)
			(effects
				(font
					(size 1.016 1.016)
					(thickness 0.1524)
				)
			)
		)
		(property "Device Type" "R402H16"
			(at 0.064008 -5.517896 270)
			(unlocked yes)
			(layer "F.Fab")
			(hide yes)
			(effects
				(font
					(size 1.016 1.016)
					(thickness 0.1524)
				)
			)
		)
		(duplicate_pad_numbers_are_jumpers no)
		(fp_line
			(start -0.508 -0.9398)
			(end -0.508 0.9398)
			(stroke
				(width 0.1524)
				(type default)
			)
			(layer "F.SilkS")
		)
		(fp_line
			(start 0.508 -0.9398)
			(end -0.508 -0.9398)
			(stroke
				(width 0.1524)
				(type default)
			)
			(layer "F.SilkS")
		)
		(fp_rect
			(start -0.508 0.9398)
			(end 0.508 -0.9398)
			(stroke
				(width 0)
				(type default)
			)
			(fill no)
			(layer "F.CrtYd")
		)
		(fp_rect
			(start -0.508 0.9398)
			(end 0.508 -0.9398)
			(stroke
				(width 0)
				(type default)
			)
			(fill no)
			(layer "F.Fab")
		)
		(pad "1" smd custom
			(at 0 -0.4445 270)
			(size 0.1397 0.1397)
			(layers "F.Cu" "F.Mask" "F.Paste")
			(net "U30_Q1")
			(options
				(clearance outline)
				(anchor circle)
			)
			(primitives
				(gr_poly
					(pts
						(arc
							(start -0.1778 -0.2794)
							(mid -0.249642 -0.249642)
							(end -0.2794 -0.1778)
						)
						(arc
							(start -0.2794 0.1778)
							(mid -0.249642 0.249642)
							(end -0.1778 0.2794)
						)
						(arc
							(start 0.1778 0.2794)
							(mid 0.249642 0.249642)
							(end 0.2794 0.1778)
						)
						(arc
							(start 0.2794 -0.1778)
							(mid 0.249642 -0.249642)
							(end 0.1778 -0.2794)
						)
					)
					(width 0)
					(fill yes)
				)
			)
		)
		(pad "2" smd custom
			(at 0 0.4445 270)
			(size 0.1397 0.1397)
			(layers "F.Cu" "F.Mask" "F.Paste")
			(net "CLK_50M_BMC_NCSI")
			(options
				(clearance outline)
				(anchor circle)
			)
			(primitives
				(gr_poly
					(pts
						(arc
							(start -0.1778 -0.2794)
							(mid -0.249642 -0.249642)
							(end -0.2794 -0.1778)
						)
						(arc
							(start -0.2794 0.1778)
							(mid -0.249642 0.249642)
							(end -0.1778 0.2794)
						)
						(arc
							(start 0.1778 0.2794)
							(mid 0.249642 0.249642)
							(end 0.2794 0.1778)
						)
						(arc
							(start 0.2794 -0.1778)
							(mid 0.249642 -0.249642)
							(end 0.1778 -0.2794)
						)
					)
					(width 0)
					(fill yes)
				)
			)
		)
	)
	(footprint ""
		(layer "F.Cu")
		(at 185.053986 -120.928892)
		(property "Reference" "C276"
			(at 0 0 0)
			(layer "F.SilkS")
			(hide yes)
			(effects
				(font
					(size 1.27 1.27)
				)
			)
		)
		(property "Value" "SC4700P25V2KX-3-GP"
			(at 1.1811 -2.7051 0)
			(unlocked yes)
			(layer "F.Fab")
			(hide yes)
			(effects
				(font
					(size 1.016 1.016)
					(thickness 0.1524)
				)
			)
		)
		(property "Device Type" "C402H24"
			(at 1.1811 -4.2291 0)
			(unlocked yes)
			(layer "F.Fab")
			(hide yes)
			(effects
				(font
					(size 1.016 1.016)
					(thickness 0.1524)
				)
			)
		)
		(duplicate_pad_numbers_are_jumpers no)
		(fp_rect
			(start -0.4318 0.9525)
			(end 0.4318 -0.9525)
			(stroke
				(width 0)
				(type default)
			)
			(fill no)
			(layer "F.CrtYd")
		)
		(fp_rect
			(start -0.4318 0.9525)
			(end 0.4318 -0.9525)
			(stroke
				(width 0)
				(type default)
			)
			(fill no)
			(layer "F.Fab")
		)
		(pad "1" smd custom
			(at 0 -0.4445)
			(size 0.1524 0.1524)
			(layers "F.Cu" "F.Mask" "F.Paste")
			(net "VT235_VDDH")
			(options
				(clearance outline)
				(anchor circle)
			)
			(primitives
				(gr_poly
					(pts
						(arc
							(start 0.3048 -0.2032)
							(mid 0.275042 -0.275042)
							(end 0.2032 -0.3048)
						)
						(arc
							(start -0.2032 -0.3048)
							(mid -0.275042 -0.275042)
							(end -0.3048 -0.2032)
						)
						(arc
							(start -0.3048 0.2032)
							(mid -0.275042 0.275042)
							(end -0.2032 0.3048)
						)
						(arc
							(start 0.2032 0.3048)
							(mid 0.275042 0.275042)
							(end 0.3048 0.2032)
						)
					)
					(width 0)
					(fill yes)
				)
			)
		)
		(pad "2" smd custom
			(at 0 0.4445)
			(size 0.1524 0.1524)
			(layers "F.Cu" "F.Mask" "F.Paste")
			(net "GND")
			(options
				(clearance outline)
				(anchor circle)
			)
			(primitives
				(gr_poly
					(pts
						(arc
							(start 0.3048 -0.2032)
							(mid 0.275042 -0.275042)
							(end 0.2032 -0.3048)
						)
						(arc
							(start -0.2032 -0.3048)
							(mid -0.275042 -0.275042)
							(end -0.3048 -0.2032)
						)
						(arc
							(start -0.3048 0.2032)
							(mid -0.275042 0.275042)
							(end -0.2032 0.3048)
						)
						(arc
							(start 0.2032 0.3048)
							(mid 0.275042 0.275042)
							(end 0.3048 0.2032)
						)
					)
					(width 0)
					(fill yes)
				)
			)
		)
	)
	(footprint ""
		(layer "F.Cu")
		(at 46.56328 -121.868692 180)
		(property "Reference" "R90"
			(at 0 0 180)
			(layer "F.SilkS")
			(hide yes)
			(effects
				(font
					(size 1.27 1.27)
				)
			)
		)
		(property "Value" "2K2R2J-2-GP"
			(at 0.064008 -3.993896 180)
			(unlocked yes)
			(layer "F.Fab")
			(hide yes)
			(effects
				(font
					(size 1.016 1.016)
					(thickness 0.1524)
				)
			)
		)
		(property "Device Type" "R402H16"
			(at 0.064008 -5.517896 180)
			(unlocked yes)
			(layer "F.Fab")
			(hide yes)
			(effects
				(font
					(size 1.016 1.016)
					(thickness 0.1524)
				)
			)
		)
		(duplicate_pad_numbers_are_jumpers no)
		(fp_line
			(start 0.508 -0.9398)
			(end -0.508 -0.9398)
			(stroke
				(width 0.1524)
				(type default)
			)
			(layer "F.SilkS")
		)
		(fp_line
			(start -0.508 -0.9398)
			(end -0.508 0.9398)
			(stroke
				(width 0.1524)
				(type default)
			)
			(layer "F.SilkS")
		)
		(fp_rect
			(start -0.508 0.9398)
			(end 0.508 -0.9398)
			(stroke
				(width 0)
				(type default)
			)
			(fill no)
			(layer "F.CrtYd")
		)
		(fp_rect
			(start -0.508 0.9398)
			(end 0.508 -0.9398)
			(stroke
				(width 0)
				(type default)
			)
			(fill no)
			(layer "F.Fab")
		)
		(pad "1" smd custom
			(at 0 -0.4445 180)
			(size 0.1397 0.1397)
			(layers "F.Cu" "F.Mask" "F.Paste")
			(net "P3V3_STBY")
			(options
				(clearance outline)
				(anchor circle)
			)
			(primitives
				(gr_poly
					(pts
						(arc
							(start -0.1778 -0.2794)
							(mid -0.249642 -0.249642)
							(end -0.2794 -0.1778)
						)
						(arc
							(start -0.2794 0.1778)
							(mid -0.249642 0.249642)
							(end -0.1778 0.2794)
						)
						(arc
							(start 0.1778 0.2794)
							(mid 0.249642 0.249642)
							(end 0.2794 0.1778)
						)
						(arc
							(start 0.2794 -0.1778)
							(mid 0.249642 -0.249642)
							(end 0.1778 -0.2794)
						)
					)
					(width 0)
					(fill yes)
				)
			)
		)
		(pad "2" smd custom
			(at 0 0.4445 180)
			(size 0.1397 0.1397)
			(layers "F.Cu" "F.Mask" "F.Paste")
			(net "BMC_CPU_EN")
			(options
				(clearance outline)
				(anchor circle)
			)
			(primitives
				(gr_poly
					(pts
						(arc
							(start -0.1778 -0.2794)
							(mid -0.249642 -0.249642)
							(end -0.2794 -0.1778)
						)
						(arc
							(start -0.2794 0.1778)
							(mid -0.249642 0.249642)
							(end -0.1778 0.2794)
						)
						(arc
							(start 0.1778 0.2794)
							(mid 0.249642 0.249642)
							(end 0.2794 0.1778)
						)
						(arc
							(start 0.2794 -0.1778)
							(mid 0.249642 -0.249642)
							(end 0.1778 -0.2794)
						)
					)
					(width 0)
					(fill yes)
				)
			)
		)
	)
	(footprint ""
		(layer "F.Cu")
		(at 8.65378 -12.97178)
		(property "Reference" "D3"
			(at 0 0 0)
			(layer "F.SilkS")
			(hide yes)
			(effects
				(font
					(size 1.27 1.27)
				)
			)
		)
		(property "Value" "PESD5V0X1UAB-GP"
			(at 0 -4.690618 0)
			(unlocked yes)
			(layer "F.Fab")
			(hide yes)
			(effects
				(font
					(size 1.016 1.016)
					(thickness 0.1524)
				)
			)
		)
		(property "Device Type" "SOD523AKH26"
			(at 0 -6.214618 0)
			(unlocked yes)
			(layer "F.Fab")
			(hide yes)
			(effects
				(font
					(size 1.016 1.016)
					(thickness 0.1524)
				)
			)
		)
		(duplicate_pad_numbers_are_jumpers no)
		(fp_line
			(start -0.5334 -1.4478)
			(end 0.5334 -1.4478)
			(stroke
				(width 0.1524)
				(type default)
			)
			(layer "F.SilkS")
		)
		(fp_line
			(start -0.5334 1.524)
			(end -0.5334 -1.4478)
			(stroke
				(width 0.1524)
				(type default)
			)
			(layer "F.SilkS")
		)
		(fp_line
			(start 0.4064 1.651)
			(end -0.4064 1.651)
			(stroke
				(width 0.4064)
				(type default)
			)
			(layer "F.SilkS")
		)
		(fp_line
			(start 0.5334 -1.4478)
			(end 0.5334 1.524)
			(stroke
				(width 0.1524)
				(type default)
			)
			(layer "F.SilkS")
		)
		(fp_line
			(start 0.5334 1.524)
			(end -0.5334 1.524)
			(stroke
				(width 0.1524)
				(type default)
			)
			(layer "F.SilkS")
		)
		(fp_rect
			(start -0.6096 1.8542)
			(end 0.6096 -1.524)
			(stroke
				(width 0)
				(type default)
			)
			(fill no)
			(layer "F.CrtYd")
		)
		(fp_poly
			(pts
				(xy -0.6096 -1.524) (xy 0.6096 -1.524) (xy 0.6096 1.8542) (xy -0.6096 1.8542)
			)
			(stroke
				(width 0)
				(type default)
			)
			(fill no)
			(layer "F.Fab")
		)
		(pad "A" smd rect
			(at 0 -0.762)
			(size 0.5588 1.016)
			(layers "F.Cu" "F.Mask" "F.Paste")
			(net "GND")
		)
		(pad "K" smd rect
			(at 0 0.762)
			(size 0.5588 1.016)
			(layers "F.Cu" "F.Mask" "F.Paste")
			(net "SYS_RST_BTN_IN_N")
		)
	)
)
